(kicad_pcb
	(version 20260206)
	(generator "pcbnew")
	(generator_version "10.0")
	(general
		(thickness 1.6)
		(legacy_teardrops no)
	)
	(paper "A4")
	(title_block
		(title "03242023_DA0F0TMBIJ0_F0T_Motherboard_J_brd_V01_OCP.brd")
		(comment 1 "Grand Teton / footprints 6051-6056 of 6105")
	)
	(layers
		(0 "F.Cu" signal "TOP")
		(4 "In1.Cu" signal "GND")
		(6 "In2.Cu" signal "IN1")
		(8 "In3.Cu" signal "GND1")
		(10 "In4.Cu" signal "IN2")
		(12 "In5.Cu" signal "GND2")
		(14 "In6.Cu" signal "IN3")
		(16 "In7.Cu" signal "GND3")
		(18 "In8.Cu" signal "VCC")
		(20 "In9.Cu" signal "VCC1")
		(22 "In10.Cu" signal "GND4")
		(24 "In11.Cu" signal "IN4")
		(26 "In12.Cu" signal "GND5")
		(28 "In13.Cu" signal "IN5")
		(30 "In14.Cu" signal "GND6")
		(32 "In15.Cu" signal "IN6")
		(34 "In16.Cu" signal "GND7")
		(2 "B.Cu" signal "BOTTOM")
		(9 "F.Adhes" user "F.Adhesive")
		(11 "B.Adhes" user "B.Adhesive")
		(13 "F.Paste" user "Package Geometry/Pastemask Top")
		(15 "B.Paste" user "Package Geometry/Pastemask Bottom")
		(5 "F.SilkS" user "Ref Des/Silkscreen Top")
		(7 "B.SilkS" user "Ref Des/Silkscreen Bottom")
		(1 "F.Mask" user "Board Geometry/Soldermask Top")
		(3 "B.Mask" user "Board Geometry/Soldermask Bottom")
		(17 "Dwgs.User" user "User.Drawings")
		(19 "Cmts.User" user "User.Comments")
		(21 "Eco1.User" user "User.Eco1")
		(23 "Eco2.User" user "User.Eco2")
		(25 "Edge.Cuts" user "Board Geometry/Outline")
		(27 "Margin" user)
		(31 "F.CrtYd" user "Package Geometry/Place Bound Top")
		(29 "B.CrtYd" user "Package Geometry/Place Bound Bottom")
		(35 "F.Fab" user "Ref Des/Assembly Top")
		(33 "B.Fab" user "Ref Des/Assembly Bottom")
	)
	(footprint ""
		(layer "B.Cu")
		(at 183.172608 -398.651222)
		(property "Reference" "PR3932"
			(at 0 0 0)
			(layer "B.SilkS")
			(hide yes)
			(effects
				(font
					(size 1.27 1.27)
				)
				(justify mirror)
			)
		)
		(property "Value" ""
			(at 0 0 0)
			(layer "B.Fab")
			(effects
				(font
					(size 1.27 1.27)
				)
				(justify mirror)
			)
		)
		(duplicate_pad_numbers_are_jumpers no)
		(fp_line
			(start -0.7874 -0.4064)
			(end -0.7874 0.4064)
			(stroke
				(width 0.1524)
				(type default)
			)
			(layer "B.SilkS")
		)
		(fp_line
			(start -0.7874 0.4064)
			(end 0.7874 0.4064)
			(stroke
				(width 0.1524)
				(type default)
			)
			(layer "B.SilkS")
		)
		(fp_line
			(start 0.7874 -0.4064)
			(end -0.7874 -0.4064)
			(stroke
				(width 0.1524)
				(type default)
			)
			(layer "B.SilkS")
		)
		(fp_line
			(start 0.7874 0.4064)
			(end 0.7874 -0.4064)
			(stroke
				(width 0.1524)
				(type default)
			)
			(layer "B.SilkS")
		)
		(fp_line
			(start -0.67945 -0.3048)
			(end -0.67945 0.3048)
			(stroke
				(width 0.1)
				(type default)
			)
			(layer "B.Fab")
		)
		(fp_line
			(start -0.67945 0.3048)
			(end -0.120396 0.3048)
			(stroke
				(width 0.1)
				(type default)
			)
			(layer "B.Fab")
		)
		(fp_line
			(start -0.12065 -0.3048)
			(end -0.67945 -0.3048)
			(stroke
				(width 0.1)
				(type default)
			)
			(layer "B.Fab")
		)
		(fp_line
			(start -0.12065 -0.2794)
			(end -0.12065 -0.3048)
			(stroke
				(width 0.1)
				(type default)
			)
			(layer "B.Fab")
		)
		(fp_line
			(start -0.120396 0.2794)
			(end 0.12065 0.2794)
			(stroke
				(width 0.1)
				(type default)
			)
			(layer "B.Fab")
		)
		(fp_line
			(start -0.120396 0.3048)
			(end -0.120396 0.2794)
			(stroke
				(width 0.1)
				(type default)
			)
			(layer "B.Fab")
		)
		(fp_line
			(start 0.12065 -0.305054)
			(end 0.12065 -0.2794)
			(stroke
				(width 0.1)
				(type default)
			)
			(layer "B.Fab")
		)
		(fp_line
			(start 0.12065 -0.2794)
			(end -0.12065 -0.2794)
			(stroke
				(width 0.1)
				(type default)
			)
			(layer "B.Fab")
		)
		(fp_line
			(start 0.12065 0.2794)
			(end 0.12065 0.3048)
			(stroke
				(width 0.1)
				(type default)
			)
			(layer "B.Fab")
		)
		(fp_line
			(start 0.12065 0.3048)
			(end 0.67945 0.3048)
			(stroke
				(width 0.1)
				(type default)
			)
			(layer "B.Fab")
		)
		(fp_line
			(start 0.67945 -0.305054)
			(end 0.12065 -0.305054)
			(stroke
				(width 0.1)
				(type default)
			)
			(layer "B.Fab")
		)
		(fp_line
			(start 0.67945 0.3048)
			(end 0.67945 -0.305054)
			(stroke
				(width 0.1)
				(type default)
			)
			(layer "B.Fab")
		)
		(pad "1" smd circle
			(at 0.40005 0 180)
			(size 0 0)
			(layers "B.Cu" "B.Mask" "B.Paste")
			(net "HSC_VOSEN")
		)
		(pad "2" smd circle
			(at -0.40005 0 180)
			(size 0 0)
			(layers "B.Cu" "B.Mask" "B.Paste")
			(net "AGND_HSC")
		)
	)
	(footprint ""
		(layer "B.Cu")
		(at 160.83788 -123.916948)
		(property "Reference" "R988"
			(at 0 0 0)
			(layer "B.SilkS")
			(hide yes)
			(effects
				(font
					(size 1.27 1.27)
				)
				(justify mirror)
			)
		)
		(property "Value" ""
			(at 0 0 0)
			(layer "B.Fab")
			(effects
				(font
					(size 1.27 1.27)
				)
				(justify mirror)
			)
		)
		(duplicate_pad_numbers_are_jumpers no)
		(fp_line
			(start -0.7874 -0.4064)
			(end -0.7874 0.4064)
			(stroke
				(width 0.1524)
				(type default)
			)
			(layer "B.SilkS")
		)
		(fp_line
			(start -0.7874 0.4064)
			(end 0.7874 0.4064)
			(stroke
				(width 0.1524)
				(type default)
			)
			(layer "B.SilkS")
		)
		(fp_line
			(start 0.7874 -0.4064)
			(end -0.7874 -0.4064)
			(stroke
				(width 0.1524)
				(type default)
			)
			(layer "B.SilkS")
		)
		(fp_line
			(start 0.7874 0.4064)
			(end 0.7874 -0.4064)
			(stroke
				(width 0.1524)
				(type default)
			)
			(layer "B.SilkS")
		)
		(fp_line
			(start -0.67945 -0.3048)
			(end -0.67945 0.3048)
			(stroke
				(width 0.1)
				(type default)
			)
			(layer "B.Fab")
		)
		(fp_line
			(start -0.67945 0.3048)
			(end -0.120396 0.3048)
			(stroke
				(width 0.1)
				(type default)
			)
			(layer "B.Fab")
		)
		(fp_line
			(start -0.12065 -0.3048)
			(end -0.67945 -0.3048)
			(stroke
				(width 0.1)
				(type default)
			)
			(layer "B.Fab")
		)
		(fp_line
			(start -0.12065 -0.2794)
			(end -0.12065 -0.3048)
			(stroke
				(width 0.1)
				(type default)
			)
			(layer "B.Fab")
		)
		(fp_line
			(start -0.120396 0.2794)
			(end 0.12065 0.2794)
			(stroke
				(width 0.1)
				(type default)
			)
			(layer "B.Fab")
		)
		(fp_line
			(start -0.120396 0.3048)
			(end -0.120396 0.2794)
			(stroke
				(width 0.1)
				(type default)
			)
			(layer "B.Fab")
		)
		(fp_line
			(start 0.12065 -0.305054)
			(end 0.12065 -0.2794)
			(stroke
				(width 0.1)
				(type default)
			)
			(layer "B.Fab")
		)
		(fp_line
			(start 0.12065 -0.2794)
			(end -0.12065 -0.2794)
			(stroke
				(width 0.1)
				(type default)
			)
			(layer "B.Fab")
		)
		(fp_line
			(start 0.12065 0.2794)
			(end 0.12065 0.3048)
			(stroke
				(width 0.1)
				(type default)
			)
			(layer "B.Fab")
		)
		(fp_line
			(start 0.12065 0.3048)
			(end 0.67945 0.3048)
			(stroke
				(width 0.1)
				(type default)
			)
			(layer "B.Fab")
		)
		(fp_line
			(start 0.67945 -0.305054)
			(end 0.12065 -0.305054)
			(stroke
				(width 0.1)
				(type default)
			)
			(layer "B.Fab")
		)
		(fp_line
			(start 0.67945 0.3048)
			(end 0.67945 -0.305054)
			(stroke
				(width 0.1)
				(type default)
			)
			(layer "B.Fab")
		)
		(pad "1" smd circle
			(at 0.40005 0 180)
			(size 0 0)
			(layers "B.Cu" "B.Mask" "B.Paste")
			(net "FM_PVCCFA_EHV_FIVRA_CPU1_R_EN")
		)
		(pad "2" smd circle
			(at -0.40005 0 180)
			(size 0 0)
			(layers "B.Cu" "B.Mask" "B.Paste")
			(net "FM_PVCCFA_EHV_FIVRA_CPU1_EN")
		)
	)
	(footprint ""
		(layer "B.Cu")
		(at 126.89586 -22.794468 90)
		(property "Reference" "R4292"
			(at 0 0 90)
			(layer "B.SilkS")
			(hide yes)
			(effects
				(font
					(size 1.27 1.27)
				)
				(justify mirror)
			)
		)
		(property "Value" ""
			(at 0 0 90)
			(layer "B.Fab")
			(effects
				(font
					(size 1.27 1.27)
				)
				(justify mirror)
			)
		)
		(duplicate_pad_numbers_are_jumpers no)
		(fp_line
			(start 0.7874 -0.4064)
			(end -0.7874 -0.4064)
			(stroke
				(width 0.1524)
				(type default)
			)
			(layer "B.SilkS")
		)
		(fp_line
			(start -0.7874 -0.4064)
			(end -0.7874 0.4064)
			(stroke
				(width 0.1524)
				(type default)
			)
			(layer "B.SilkS")
		)
		(fp_line
			(start 0.7874 0.4064)
			(end 0.7874 -0.4064)
			(stroke
				(width 0.1524)
				(type default)
			)
			(layer "B.SilkS")
		)
		(fp_line
			(start -0.7874 0.4064)
			(end 0.7874 0.4064)
			(stroke
				(width 0.1524)
				(type default)
			)
			(layer "B.SilkS")
		)
		(fp_line
			(start 0.67945 -0.305054)
			(end 0.12065 -0.305054)
			(stroke
				(width 0.1)
				(type default)
			)
			(layer "B.Fab")
		)
		(fp_line
			(start 0.12065 -0.305054)
			(end 0.12065 -0.2794)
			(stroke
				(width 0.1)
				(type default)
			)
			(layer "B.Fab")
		)
		(fp_line
			(start -0.12065 -0.3048)
			(end -0.67945 -0.3048)
			(stroke
				(width 0.1)
				(type default)
			)
			(layer "B.Fab")
		)
		(fp_line
			(start -0.67945 -0.3048)
			(end -0.67945 0.3048)
			(stroke
				(width 0.1)
				(type default)
			)
			(layer "B.Fab")
		)
		(fp_line
			(start 0.12065 -0.2794)
			(end -0.12065 -0.2794)
			(stroke
				(width 0.1)
				(type default)
			)
			(layer "B.Fab")
		)
		(fp_line
			(start -0.12065 -0.2794)
			(end -0.12065 -0.3048)
			(stroke
				(width 0.1)
				(type default)
			)
			(layer "B.Fab")
		)
		(fp_line
			(start 0.12065 0.2794)
			(end 0.12065 0.3048)
			(stroke
				(width 0.1)
				(type default)
			)
			(layer "B.Fab")
		)
		(fp_line
			(start -0.120396 0.2794)
			(end 0.12065 0.2794)
			(stroke
				(width 0.1)
				(type default)
			)
			(layer "B.Fab")
		)
		(fp_line
			(start 0.67945 0.3048)
			(end 0.67945 -0.305054)
			(stroke
				(width 0.1)
				(type default)
			)
			(layer "B.Fab")
		)
		(fp_line
			(start 0.12065 0.3048)
			(end 0.67945 0.3048)
			(stroke
				(width 0.1)
				(type default)
			)
			(layer "B.Fab")
		)
		(fp_line
			(start -0.120396 0.3048)
			(end -0.120396 0.2794)
			(stroke
				(width 0.1)
				(type default)
			)
			(layer "B.Fab")
		)
		(fp_line
			(start -0.67945 0.3048)
			(end -0.120396 0.3048)
			(stroke
				(width 0.1)
				(type default)
			)
			(layer "B.Fab")
		)
		(pad "1" smd circle
			(at 0.40005 0 270)
			(size 0 0)
			(layers "B.Cu" "B.Mask" "B.Paste")
			(net "FM_USB3_1_EN_N")
		)
		(pad "2" smd circle
			(at -0.40005 0 270)
			(size 0 0)
			(layers "B.Cu" "B.Mask" "B.Paste")
			(net "GND")
		)
	)
	(footprint ""
		(layer "B.Cu")
		(at 365.438436 -324.911466 -90)
		(property "Reference" "PC291_P0_3"
			(at 0 0 90)
			(layer "B.SilkS")
			(hide yes)
			(effects
				(font
					(size 1.27 1.27)
				)
				(justify mirror)
			)
		)
		(property "Value" ""
			(at 0 0 90)
			(layer "B.Fab")
			(effects
				(font
					(size 1.27 1.27)
				)
				(justify mirror)
			)
		)
		(duplicate_pad_numbers_are_jumpers no)
		(fp_line
			(start -1.524 0.762)
			(end 1.524 0.762)
			(stroke
				(width 0.1524)
				(type default)
			)
			(layer "B.SilkS")
		)
		(fp_line
			(start 1.524 0.762)
			(end 1.524 -0.762)
			(stroke
				(width 0.1524)
				(type default)
			)
			(layer "B.SilkS")
		)
		(fp_line
			(start -1.524 -0.762)
			(end -1.524 0.762)
			(stroke
				(width 0.1524)
				(type default)
			)
			(layer "B.SilkS")
		)
		(fp_line
			(start 1.524 -0.762)
			(end -1.524 -0.762)
			(stroke
				(width 0.1524)
				(type default)
			)
			(layer "B.SilkS")
		)
		(fp_line
			(start -1.1049 0.724916)
			(end -1.1049 -0.724916)
			(stroke
				(width 0.1)
				(type default)
			)
			(layer "B.Fab")
		)
		(fp_line
			(start 1.1049 0.724916)
			(end -1.1049 0.724916)
			(stroke
				(width 0.1)
				(type default)
			)
			(layer "B.Fab")
		)
		(fp_line
			(start -1.1049 -0.724916)
			(end 1.1049 -0.724916)
			(stroke
				(width 0.1)
				(type default)
			)
			(layer "B.Fab")
		)
		(fp_line
			(start 1.1049 -0.724916)
			(end 1.1049 0.724916)
			(stroke
				(width 0.1)
				(type default)
			)
			(layer "B.Fab")
		)
		(pad "1" smd rect
			(at 0.889 0 270)
			(size 1.016 1.27)
			(layers "B.Cu" "B.Mask" "B.Paste")
			(net "PVCCIN_CPU0")
		)
		(pad "2" smd rect
			(at -0.889 0 270)
			(size 1.016 1.27)
			(layers "B.Cu" "B.Mask" "B.Paste")
			(net "GND")
		)
	)
	(footprint ""
		(layer "B.Cu")
		(at 365.037624 -183.101488 90)
		(property "Reference" "Q15"
			(at 2.23901 -2.577084 0)
			(unlocked yes)
			(layer "B.SilkS")
			(effects
				(font
					(size 0.7874 0.5842)
					(thickness 0.1524)
				)
				(justify left mirror)
			)
		)
		(property "Value" ""
			(at 0 0 90)
			(layer "B.Fab")
			(effects
				(font
					(size 1.27 1.27)
				)
				(justify mirror)
			)
		)
		(duplicate_pad_numbers_are_jumpers no)
		(fp_line
			(start 1.332738 -1.100074)
			(end 0.4826 -1.100074)
			(stroke
				(width 0.1524)
				(type default)
			)
			(layer "B.SilkS")
		)
		(fp_line
			(start 0.4826 -1.100074)
			(end 0 -0.541274)
			(stroke
				(width 0.1524)
				(type default)
			)
			(layer "B.SilkS")
		)
		(fp_line
			(start -0.4826 -1.100074)
			(end -1.332738 -1.100074)
			(stroke
				(width 0.1524)
				(type default)
			)
			(layer "B.SilkS")
		)
		(fp_line
			(start -1.332738 -1.100074)
			(end -1.332738 1.100074)
			(stroke
				(width 0.1524)
				(type default)
			)
			(layer "B.SilkS")
		)
		(fp_line
			(start 0 -0.541274)
			(end -0.4826 -1.100074)
			(stroke
				(width 0.1524)
				(type default)
			)
			(layer "B.SilkS")
		)
		(fp_line
			(start 1.332738 1.100074)
			(end 1.332738 -1.100074)
			(stroke
				(width 0.1524)
				(type default)
			)
			(layer "B.SilkS")
		)
		(fp_line
			(start -1.332738 1.100074)
			(end 1.332738 1.100074)
			(stroke
				(width 0.1524)
				(type default)
			)
			(layer "B.SilkS")
		)
		(fp_poly
			(pts
				(xy 2.2352 -0.298958) (xy 1.533144 -0.649986) (xy 2.2352 -1.001014)
			)
			(stroke
				(width 0)
				(type default)
			)
			(fill yes)
			(layer "B.SilkS")
		)
		(fp_line
			(start 0.674878 -1.100074)
			(end -0.674878 -1.100074)
			(stroke
				(width 0.1)
				(type default)
			)
			(layer "B.Fab")
		)
		(fp_line
			(start -0.674878 -1.100074)
			(end -0.674878 1.100074)
			(stroke
				(width 0.1)
				(type default)
			)
			(layer "B.Fab")
		)
		(fp_line
			(start 0.674878 1.100074)
			(end 0.674878 -1.100074)
			(stroke
				(width 0.1)
				(type default)
			)
			(layer "B.Fab")
		)
		(fp_line
			(start -0.674878 1.100074)
			(end 0.674878 1.100074)
			(stroke
				(width 0.1)
				(type default)
			)
			(layer "B.Fab")
		)
		(fp_poly
			(pts
				(xy 2.2352 -0.298958) (xy 2.2352 -1.001014) (xy 1.533144 -0.649986)
			)
			(stroke
				(width 0)
				(type default)
			)
			(fill yes)
			(layer "B.Fab")
		)
		(pad "1" smd rect
			(at 0.94996 -0.649986 180)
			(size 0.4318 0.508)
			(layers "B.Cu" "B.Mask" "B.Paste")
			(net "GND")
		)
		(pad "2" smd rect
			(at 0.94996 0 180)
			(size 0.4318 0.508)
			(layers "B.Cu" "B.Mask" "B.Paste")
			(net "FM_SMB_PEHPCPU0_PCIE_ALERT_R_N")
		)
		(pad "3" smd rect
			(at 0.94996 0.649986 180)
			(size 0.4318 0.508)
			(layers "B.Cu" "B.Mask" "B.Paste")
			(net "FM_PEHPCPU0_ALERT_N")
		)
		(pad "4" smd rect
			(at -0.94996 0.649986 180)
			(size 0.4318 0.508)
			(layers "B.Cu" "B.Mask" "B.Paste")
			(net "GND")
		)
		(pad "5" smd rect
			(at -0.94996 0 180)
			(size 0.4318 0.508)
			(layers "B.Cu" "B.Mask" "B.Paste")
			(net "FM_SMB_CPU0_ALERT_R1")
		)
		(pad "6" smd rect
			(at -0.94996 -0.649986 180)
			(size 0.4318 0.508)
			(layers "B.Cu" "B.Mask" "B.Paste")
			(net "FM_SMB_CPU0_ALERT_R1")
		)
	)
	(footprint ""
		(layer "B.Cu")
		(at 318.554862 -191.122046 180)
		(property "Reference" "R1009"
			(at 0 0 0)
			(layer "B.SilkS")
			(hide yes)
			(effects
				(font
					(size 1.27 1.27)
				)
				(justify mirror)
			)
		)
		(property "Value" ""
			(at 0 0 0)
			(layer "B.Fab")
			(effects
				(font
					(size 1.27 1.27)
				)
				(justify mirror)
			)
		)
		(duplicate_pad_numbers_are_jumpers no)
		(fp_line
			(start 0.7874 0.4064)
			(end 0.7874 -0.4064)
			(stroke
				(width 0.1524)
				(type default)
			)
			(layer "B.SilkS")
		)
		(fp_line
			(start 0.7874 -0.4064)
			(end -0.7874 -0.4064)
			(stroke
				(width 0.1524)
				(type default)
			)
			(layer "B.SilkS")
		)
		(fp_line
			(start -0.7874 0.4064)
			(end 0.7874 0.4064)
			(stroke
				(width 0.1524)
				(type default)
			)
			(layer "B.SilkS")
		)
		(fp_line
			(start -0.7874 -0.4064)
			(end -0.7874 0.4064)
			(stroke
				(width 0.1524)
				(type default)
			)
			(layer "B.SilkS")
		)
		(fp_line
			(start 0.67945 0.3048)
			(end 0.67945 -0.305054)
			(stroke
				(width 0.1)
				(type default)
			)
			(layer "B.Fab")
		)
		(fp_line
			(start 0.67945 -0.305054)
			(end 0.12065 -0.305054)
			(stroke
				(width 0.1)
				(type default)
			)
			(layer "B.Fab")
		)
		(fp_line
			(start 0.12065 0.3048)
			(end 0.67945 0.3048)
			(stroke
				(width 0.1)
				(type default)
			)
			(layer "B.Fab")
		)
		(fp_line
			(start 0.12065 0.2794)
			(end 0.12065 0.3048)
			(stroke
				(width 0.1)
				(type default)
			)
			(layer "B.Fab")
		)
		(fp_line
			(start 0.12065 -0.2794)
			(end -0.12065 -0.2794)
			(stroke
				(width 0.1)
				(type default)
			)
			(layer "B.Fab")
		)
		(fp_line
			(start 0.12065 -0.305054)
			(end 0.12065 -0.2794)
			(stroke
				(width 0.1)
				(type default)
			)
			(layer "B.Fab")
		)
		(fp_line
			(start -0.120396 0.3048)
			(end -0.120396 0.2794)
			(stroke
				(width 0.1)
				(type default)
			)
			(layer "B.Fab")
		)
		(fp_line
			(start -0.120396 0.2794)
			(end 0.12065 0.2794)
			(stroke
				(width 0.1)
				(type default)
			)
			(layer "B.Fab")
		)
		(fp_line
			(start -0.12065 -0.2794)
			(end -0.12065 -0.3048)
			(stroke
				(width 0.1)
				(type default)
			)
			(layer "B.Fab")
		)
		(fp_line
			(start -0.12065 -0.3048)
			(end -0.67945 -0.3048)
			(stroke
				(width 0.1)
				(type default)
			)
			(layer "B.Fab")
		)
		(fp_line
			(start -0.67945 0.3048)
			(end -0.120396 0.3048)
			(stroke
				(width 0.1)
				(type default)
			)
			(layer "B.Fab")
		)
		(fp_line
			(start -0.67945 -0.3048)
			(end -0.67945 0.3048)
			(stroke
				(width 0.1)
				(type default)
			)
			(layer "B.Fab")
		)
		(pad "1" smd circle
			(at 0.40005 0)
			(size 0 0)
			(layers "B.Cu" "B.Mask" "B.Paste")
			(net "PVNN_TERM_CPU0")
		)
		(pad "2" smd circle
			(at -0.40005 0)
			(size 0 0)
			(layers "B.Cu" "B.Mask" "B.Paste")
			(net "PU_TAP_ODT_CPU0_EN")
		)
	)
)
